(kicad_pcb
	(version 20241229)
	(generator "pcbnew")
	(generator_version "9.0")
	(general
		(thickness 1.61)
		(legacy_teardrops no)
	)
	(paper "A3")
	(title_block
		(title "RDIMM DDR5 Tester")
		(date "2026-05-21")
		(rev "2.2.0")
		(company "Antmicro")
		(comment 9 "footprints 397-401 of 796")
	)
	(layers
		(0 "F.Cu" signal)
		(4 "In1.Cu" power)
		(6 "In2.Cu" mixed)
		(8 "In3.Cu" power)
		(10 "In4.Cu" mixed)
		(12 "In5.Cu" power)
		(14 "In6.Cu" mixed)
		(16 "In7.Cu" power)
		(18 "In8.Cu" power)
		(20 "In9.Cu" mixed)
		(22 "In10.Cu" power)
		(2 "B.Cu" signal)
		(9 "F.Adhes" user "F.Adhesive")
		(11 "B.Adhes" user "B.Adhesive")
		(13 "F.Paste" user)
		(15 "B.Paste" user)
		(5 "F.SilkS" user "F.Silkscreen")
		(7 "B.SilkS" user "B.Silkscreen")
		(1 "F.Mask" user)
		(3 "B.Mask" user)
		(17 "Dwgs.User" user "User.Drawings")
		(19 "Cmts.User" user "User.Comments")
		(21 "Eco1.User" user "User.Eco1")
		(23 "Eco2.User" user "User.Eco2")
		(25 "Edge.Cuts" user)
		(27 "Margin" user)
		(31 "F.CrtYd" user "F.Courtyard")
		(29 "B.CrtYd" user "B.Courtyard")
		(35 "F.Fab" user)
		(33 "B.Fab" user)
	)
	(footprint "antmicro-footprints:C_0402_1005Metric"
		(layer "B.Cu")
		(at 136.433171 146.453992 90)
		(descr "Capacitor SMD 0402")
		(tags "capacitor SMD 0402")
		(property "Reference" "C134"
			(at -3.914008 0.202829 90)
			(layer "B.SilkS")
			(effects
				(font
					(size 0.7 0.7)
					(thickness 0.15)
				)
				(justify right bottom mirror)
			)
		)
		(property "Value" "C_4u7_0402"
			(at -1.022927 -2.155213 90)
			(layer "B.Fab")
			(effects
				(font
					(size 0.7 0.7)
					(thickness 0.15)
				)
				(justify right bottom mirror)
			)
		)
		(property "Datasheet" "https://www.murata.com/products/productdetail?partno=GRM155R61A475MEAA%23"
			(at 0 0 90)
			(layer "F.Fab")
			(hide yes)
			(effects
				(font
					(size 1.27 1.27)
					(thickness 0.15)
				)
			)
		)
		(property "Manufacturer" "Murata"
			(at 0 0 90)
			(unlocked yes)
			(layer "B.Fab")
			(hide yes)
			(effects
				(font
					(size 1 1)
					(thickness 0.15)
				)
				(justify mirror)
			)
		)
		(property "MPN" "GRM155R61A475MEAAD"
			(at 0 0 90)
			(unlocked yes)
			(layer "B.Fab")
			(hide yes)
			(effects
				(font
					(size 1 1)
					(thickness 0.15)
				)
				(justify mirror)
			)
		)
		(property "Val" "4u7"
			(at 0 0 90)
			(unlocked yes)
			(layer "B.Fab")
			(hide yes)
			(effects
				(font
					(size 1 1)
					(thickness 0.15)
				)
				(justify mirror)
			)
		)
		(property "License" "Apache-2.0"
			(at 0 0 90)
			(unlocked yes)
			(layer "B.Fab")
			(hide yes)
			(effects
				(font
					(size 1 1)
					(thickness 0.15)
				)
				(justify mirror)
			)
		)
		(property "Author" "Antmicro"
			(at 0 0 90)
			(unlocked yes)
			(layer "B.Fab")
			(hide yes)
			(effects
				(font
					(size 1 1)
					(thickness 0.15)
				)
				(justify mirror)
			)
		)
		(property "Voltage" ""
			(at 0 0 90)
			(unlocked yes)
			(layer "B.Fab")
			(hide yes)
			(effects
				(font
					(size 1 1)
					(thickness 0.15)
				)
				(justify mirror)
			)
		)
		(property "Dielectric" ""
			(at 0 0 90)
			(unlocked yes)
			(layer "B.Fab")
			(hide yes)
			(effects
				(font
					(size 1 1)
					(thickness 0.15)
				)
				(justify mirror)
			)
		)
		(sheetname "/Ethernet/")
		(sheetfile "ethernet.kicad_sch")
		(attr smd)
		(fp_rect
			(start -0.925 0.47)
			(end 0.925 -0.47)
			(stroke
				(width 0.05)
				(type default)
			)
			(fill no)
			(layer "B.CrtYd")
		)
		(fp_line
			(start 0.504 -0.248)
			(end -0.494 -0.248)
			(stroke
				(width 0.15)
				(type solid)
			)
			(layer "B.Fab")
		)
		(fp_line
			(start -0.494 -0.248)
			(end -0.494 0.25)
			(stroke
				(width 0.15)
				(type solid)
			)
			(layer "B.Fab")
		)
		(fp_line
			(start 0.504 0.25)
			(end 0.504 -0.248)
			(stroke
				(width 0.15)
				(type solid)
			)
			(layer "B.Fab")
		)
		(fp_line
			(start -0.494 0.25)
			(end 0.504 0.25)
			(stroke
				(width 0.15)
				(type solid)
			)
			(layer "B.Fab")
		)
		(fp_text user "Author: Antmicro"
			(at -0.939 -3.399 270)
			(layer "B.Fab")
			(effects
				(font
					(size 0.7 0.7)
					(thickness 0.15)
				)
				(justify left bottom mirror)
			)
		)
		(fp_text user "${REFERENCE}"
			(at -0.939 -4.599 270)
			(layer "B.Fab")
			(effects
				(font
					(size 0.7 0.7)
					(thickness 0.15)
				)
				(justify left bottom mirror)
			)
		)
		(fp_text user "License: Apache-2.0"
			(at -0.939 -5.799 270)
			(layer "B.Fab")
			(effects
				(font
					(size 0.7 0.7)
					(thickness 0.15)
				)
				(justify left bottom mirror)
			)
		)
		(pad "1" smd roundrect
			(at -0.48 0 90)
			(size 0.59 0.64)
			(layers "B.Cu" "B.Mask" "B.Paste")
			(roundrect_rratio 0.25)
			(net 797 "+1V8")
			(pintype "passive")
		)
		(pad "2" smd roundrect
			(at 0.48 0 90)
			(size 0.59 0.64)
			(layers "B.Cu" "B.Mask" "B.Paste")
			(roundrect_rratio 0.25)
			(net 1 "GND")
			(pintype "passive")
		)
	)
	(footprint "antmicro-footprints:C_0402_1005Metric"
		(layer "B.Cu")
		(at 134.161328 138.732157 90)
		(descr "Capacitor SMD 0402")
		(tags "capacitor SMD 0402")
		(property "Reference" "C143"
			(at 1.176157 0.344672 90)
			(layer "B.SilkS")
			(effects
				(font
					(size 0.7 0.7)
					(thickness 0.15)
				)
				(justify right bottom mirror)
			)
		)
		(property "Value" "C_470n_0402"
			(at -1.022927 -2.155213 90)
			(layer "B.Fab")
			(effects
				(font
					(size 0.7 0.7)
					(thickness 0.15)
				)
				(justify right bottom mirror)
			)
		)
		(property "Datasheet" "https://product.tdk.com/en/search/capacitor/ceramic/mlcc/info?part_no=C1005X5R1E474M050BB"
			(at 0 0 90)
			(layer "F.Fab")
			(hide yes)
			(effects
				(font
					(size 1.27 1.27)
					(thickness 0.15)
				)
			)
		)
		(property "Manufacturer" "TDK"
			(at 0 0 90)
			(unlocked yes)
			(layer "B.Fab")
			(hide yes)
			(effects
				(font
					(size 1 1)
					(thickness 0.15)
				)
				(justify mirror)
			)
		)
		(property "MPN" "C1005X5R1E474M050BB"
			(at 0 0 90)
			(unlocked yes)
			(layer "B.Fab")
			(hide yes)
			(effects
				(font
					(size 1 1)
					(thickness 0.15)
				)
				(justify mirror)
			)
		)
		(property "Val" "470n"
			(at 0 0 90)
			(unlocked yes)
			(layer "B.Fab")
			(hide yes)
			(effects
				(font
					(size 1 1)
					(thickness 0.15)
				)
				(justify mirror)
			)
		)
		(property "License" "Apache-2.0"
			(at 0 0 90)
			(unlocked yes)
			(layer "B.Fab")
			(hide yes)
			(effects
				(font
					(size 1 1)
					(thickness 0.15)
				)
				(justify mirror)
			)
		)
		(property "Author" "Antmicro"
			(at 0 0 90)
			(unlocked yes)
			(layer "B.Fab")
			(hide yes)
			(effects
				(font
					(size 1 1)
					(thickness 0.15)
				)
				(justify mirror)
			)
		)
		(property "Voltage" ""
			(at 0 0 90)
			(unlocked yes)
			(layer "B.Fab")
			(hide yes)
			(effects
				(font
					(size 1 1)
					(thickness 0.15)
				)
				(justify mirror)
			)
		)
		(property "Dielectric" ""
			(at 0 0 90)
			(unlocked yes)
			(layer "B.Fab")
			(hide yes)
			(effects
				(font
					(size 1 1)
					(thickness 0.15)
				)
				(justify mirror)
			)
		)
		(sheetname "/Ethernet/")
		(sheetfile "ethernet.kicad_sch")
		(attr smd)
		(fp_rect
			(start -0.925 0.47)
			(end 0.925 -0.47)
			(stroke
				(width 0.05)
				(type default)
			)
			(fill no)
			(layer "B.CrtYd")
		)
		(fp_line
			(start 0.504 -0.248)
			(end -0.494 -0.248)
			(stroke
				(width 0.15)
				(type solid)
			)
			(layer "B.Fab")
		)
		(fp_line
			(start -0.494 -0.248)
			(end -0.494 0.25)
			(stroke
				(width 0.15)
				(type solid)
			)
			(layer "B.Fab")
		)
		(fp_line
			(start 0.504 0.25)
			(end 0.504 -0.248)
			(stroke
				(width 0.15)
				(type solid)
			)
			(layer "B.Fab")
		)
		(fp_line
			(start -0.494 0.25)
			(end 0.504 0.25)
			(stroke
				(width 0.15)
				(type solid)
			)
			(layer "B.Fab")
		)
		(fp_text user "License: Apache-2.0"
			(at -0.939 -5.799 270)
			(layer "B.Fab")
			(effects
				(font
					(size 0.7 0.7)
					(thickness 0.15)
				)
				(justify left bottom mirror)
			)
		)
		(fp_text user "${REFERENCE}"
			(at -0.939 -4.599 270)
			(layer "B.Fab")
			(effects
				(font
					(size 0.7 0.7)
					(thickness 0.15)
				)
				(justify left bottom mirror)
			)
		)
		(fp_text user "Author: Antmicro"
			(at -0.939 -3.399 270)
			(layer "B.Fab")
			(effects
				(font
					(size 0.7 0.7)
					(thickness 0.15)
				)
				(justify left bottom mirror)
			)
		)
		(pad "1" smd roundrect
			(at -0.48 0 90)
			(size 0.59 0.64)
			(layers "B.Cu" "B.Mask" "B.Paste")
			(roundrect_rratio 0.25)
			(net 95 "/Ethernet/AVDDL")
			(pintype "passive")
		)
		(pad "2" smd roundrect
			(at 0.48 0 90)
			(size 0.59 0.64)
			(layers "B.Cu" "B.Mask" "B.Paste")
			(roundrect_rratio 0.25)
			(net 1 "GND")
			(pintype "passive")
		)
	)
	(footprint "antmicro-footprints:C_0402_1005Metric"
		(layer "B.Cu")
		(at 132.274499 146.453992 90)
		(descr "Capacitor SMD 0402")
		(tags "capacitor SMD 0402")
		(property "Reference" "C148"
			(at -3.914008 0.202829 90)
			(layer "B.SilkS")
			(effects
				(font
					(size 0.7 0.7)
					(thickness 0.15)
				)
				(justify right bottom mirror)
			)
		)
		(property "Value" "C_470n_0402"
			(at -1.022927 -2.155213 90)
			(layer "B.Fab")
			(effects
				(font
					(size 0.7 0.7)
					(thickness 0.15)
				)
				(justify right bottom mirror)
			)
		)
		(property "Datasheet" "https://product.tdk.com/en/search/capacitor/ceramic/mlcc/info?part_no=C1005X5R1E474M050BB"
			(at 0 0 90)
			(layer "F.Fab")
			(hide yes)
			(effects
				(font
					(size 1.27 1.27)
					(thickness 0.15)
				)
			)
		)
		(property "Manufacturer" "TDK"
			(at 0 0 90)
			(unlocked yes)
			(layer "B.Fab")
			(hide yes)
			(effects
				(font
					(size 1 1)
					(thickness 0.15)
				)
				(justify mirror)
			)
		)
		(property "MPN" "C1005X5R1E474M050BB"
			(at 0 0 90)
			(unlocked yes)
			(layer "B.Fab")
			(hide yes)
			(effects
				(font
					(size 1 1)
					(thickness 0.15)
				)
				(justify mirror)
			)
		)
		(property "Val" "470n"
			(at 0 0 90)
			(unlocked yes)
			(layer "B.Fab")
			(hide yes)
			(effects
				(font
					(size 1 1)
					(thickness 0.15)
				)
				(justify mirror)
			)
		)
		(property "License" "Apache-2.0"
			(at 0 0 90)
			(unlocked yes)
			(layer "B.Fab")
			(hide yes)
			(effects
				(font
					(size 1 1)
					(thickness 0.15)
				)
				(justify mirror)
			)
		)
		(property "Author" "Antmicro"
			(at 0 0 90)
			(unlocked yes)
			(layer "B.Fab")
			(hide yes)
			(effects
				(font
					(size 1 1)
					(thickness 0.15)
				)
				(justify mirror)
			)
		)
		(property "Voltage" ""
			(at 0 0 90)
			(unlocked yes)
			(layer "B.Fab")
			(hide yes)
			(effects
				(font
					(size 1 1)
					(thickness 0.15)
				)
				(justify mirror)
			)
		)
		(property "Dielectric" ""
			(at 0 0 90)
			(unlocked yes)
			(layer "B.Fab")
			(hide yes)
			(effects
				(font
					(size 1 1)
					(thickness 0.15)
				)
				(justify mirror)
			)
		)
		(sheetname "/Ethernet/")
		(sheetfile "ethernet.kicad_sch")
		(attr smd)
		(fp_rect
			(start -0.925 0.47)
			(end 0.925 -0.47)
			(stroke
				(width 0.05)
				(type default)
			)
			(fill no)
			(layer "B.CrtYd")
		)
		(fp_line
			(start 0.504 -0.248)
			(end -0.494 -0.248)
			(stroke
				(width 0.15)
				(type solid)
			)
			(layer "B.Fab")
		)
		(fp_line
			(start -0.494 -0.248)
			(end -0.494 0.25)
			(stroke
				(width 0.15)
				(type solid)
			)
			(layer "B.Fab")
		)
		(fp_line
			(start 0.504 0.25)
			(end 0.504 -0.248)
			(stroke
				(width 0.15)
				(type solid)
			)
			(layer "B.Fab")
		)
		(fp_line
			(start -0.494 0.25)
			(end 0.504 0.25)
			(stroke
				(width 0.15)
				(type solid)
			)
			(layer "B.Fab")
		)
		(fp_text user "Author: Antmicro"
			(at -0.939 -3.399 270)
			(layer "B.Fab")
			(effects
				(font
					(size 0.7 0.7)
					(thickness 0.15)
				)
				(justify left bottom mirror)
			)
		)
		(fp_text user "License: Apache-2.0"
			(at -0.939 -5.799 270)
			(layer "B.Fab")
			(effects
				(font
					(size 0.7 0.7)
					(thickness 0.15)
				)
				(justify left bottom mirror)
			)
		)
		(fp_text user "${REFERENCE}"
			(at -0.939 -4.599 270)
			(layer "B.Fab")
			(effects
				(font
					(size 0.7 0.7)
					(thickness 0.15)
				)
				(justify left bottom mirror)
			)
		)
		(pad "1" smd roundrect
			(at -0.48 0 90)
			(size 0.59 0.64)
			(layers "B.Cu" "B.Mask" "B.Paste")
			(roundrect_rratio 0.25)
			(net 150 "+1V2")
			(pintype "passive")
		)
		(pad "2" smd roundrect
			(at 0.48 0 90)
			(size 0.59 0.64)
			(layers "B.Cu" "B.Mask" "B.Paste")
			(roundrect_rratio 0.25)
			(net 1 "GND")
			(pintype "passive")
		)
	)
	(footprint "antmicro-footprints:C_0402_1005Metric"
		(layer "B.Cu")
		(at 135.186328 138.732157 90)
		(descr "Capacitor SMD 0402")
		(tags "capacitor SMD 0402")
		(property "Reference" "C140"
			(at 1.176157 0.344672 90)
			(layer "B.SilkS")
			(effects
				(font
					(size 0.7 0.7)
					(thickness 0.15)
				)
				(justify right bottom mirror)
			)
		)
		(property "Value" "C_10n_0402"
			(at -1.022927 -2.155213 90)
			(layer "B.Fab")
			(effects
				(font
					(size 0.7 0.7)
					(thickness 0.15)
				)
				(justify right bottom mirror)
			)
		)
		(property "Datasheet" "https://www.murata.com/products/productdetail?partno=GRM155R71H103KA88%23"
			(at 0 0 90)
			(layer "F.Fab")
			(hide yes)
			(effects
				(font
					(size 1.27 1.27)
					(thickness 0.15)
				)
			)
		)
		(property "Manufacturer" "Murata"
			(at 0 0 90)
			(unlocked yes)
			(layer "B.Fab")
			(hide yes)
			(effects
				(font
					(size 1 1)
					(thickness 0.15)
				)
				(justify mirror)
			)
		)
		(property "MPN" "GRM155R71H103KA88D"
			(at 0 0 90)
			(unlocked yes)
			(layer "B.Fab")
			(hide yes)
			(effects
				(font
					(size 1 1)
					(thickness 0.15)
				)
				(justify mirror)
			)
		)
		(property "Val" "10n"
			(at 0 0 90)
			(unlocked yes)
			(layer "B.Fab")
			(hide yes)
			(effects
				(font
					(size 1 1)
					(thickness 0.15)
				)
				(justify mirror)
			)
		)
		(property "License" "Apache-2.0"
			(at 0 0 90)
			(unlocked yes)
			(layer "B.Fab")
			(hide yes)
			(effects
				(font
					(size 1 1)
					(thickness 0.15)
				)
				(justify mirror)
			)
		)
		(property "Author" "Antmicro"
			(at 0 0 90)
			(unlocked yes)
			(layer "B.Fab")
			(hide yes)
			(effects
				(font
					(size 1 1)
					(thickness 0.15)
				)
				(justify mirror)
			)
		)
		(property "Voltage" "50V"
			(at 0 0 90)
			(unlocked yes)
			(layer "B.Fab")
			(hide yes)
			(effects
				(font
					(size 1 1)
					(thickness 0.15)
				)
				(justify mirror)
			)
		)
		(property "Dielectric" "X7R"
			(at 0 0 90)
			(unlocked yes)
			(layer "B.Fab")
			(hide yes)
			(effects
				(font
					(size 1 1)
					(thickness 0.15)
				)
				(justify mirror)
			)
		)
		(sheetname "/Ethernet/")
		(sheetfile "ethernet.kicad_sch")
		(attr smd)
		(fp_rect
			(start -0.925 0.47)
			(end 0.925 -0.47)
			(stroke
				(width 0.05)
				(type default)
			)
			(fill no)
			(layer "B.CrtYd")
		)
		(fp_line
			(start 0.504 -0.248)
			(end -0.494 -0.248)
			(stroke
				(width 0.15)
				(type solid)
			)
			(layer "B.Fab")
		)
		(fp_line
			(start -0.494 -0.248)
			(end -0.494 0.25)
			(stroke
				(width 0.15)
				(type solid)
			)
			(layer "B.Fab")
		)
		(fp_line
			(start 0.504 0.25)
			(end 0.504 -0.248)
			(stroke
				(width 0.15)
				(type solid)
			)
			(layer "B.Fab")
		)
		(fp_line
			(start -0.494 0.25)
			(end 0.504 0.25)
			(stroke
				(width 0.15)
				(type solid)
			)
			(layer "B.Fab")
		)
		(fp_text user "Author: Antmicro"
			(at -0.939 -3.399 270)
			(layer "B.Fab")
			(effects
				(font
					(size 0.7 0.7)
					(thickness 0.15)
				)
				(justify left bottom mirror)
			)
		)
		(fp_text user "License: Apache-2.0"
			(at -0.939 -5.799 270)
			(layer "B.Fab")
			(effects
				(font
					(size 0.7 0.7)
					(thickness 0.15)
				)
				(justify left bottom mirror)
			)
		)
		(fp_text user "${REFERENCE}"
			(at -0.939 -4.599 270)
			(layer "B.Fab")
			(effects
				(font
					(size 0.7 0.7)
					(thickness 0.15)
				)
				(justify left bottom mirror)
			)
		)
		(pad "1" smd roundrect
			(at -0.48 0 90)
			(size 0.59 0.64)
			(layers "B.Cu" "B.Mask" "B.Paste")
			(roundrect_rratio 0.25)
			(net 95 "/Ethernet/AVDDL")
			(pintype "passive")
		)
		(pad "2" smd roundrect
			(at 0.48 0 90)
			(size 0.59 0.64)
			(layers "B.Cu" "B.Mask" "B.Paste")
			(roundrect_rratio 0.25)
			(net 1 "GND")
			(pintype "passive")
		)
	)
	(footprint "antmicro-footprints:C_0402_1005Metric"
		(layer "B.Cu")
		(at 135.433171 146.453992 90)
		(descr "Capacitor SMD 0402")
		(tags "capacitor SMD 0402")
		(property "Reference" "C141"
			(at -3.914008 0.202829 90)
			(layer "B.SilkS")
			(effects
				(font
					(size 0.7 0.7)
					(thickness 0.15)
				)
				(justify right bottom mirror)
			)
		)
		(property "Value" "C_10n_0402"
			(at -1.022927 -2.155213 90)
			(layer "B.Fab")
			(effects
				(font
					(size 0.7 0.7)
					(thickness 0.15)
				)
				(justify right bottom mirror)
			)
		)
		(property "Datasheet" "https://www.murata.com/products/productdetail?partno=GRM155R71H103KA88%23"
			(at 0 0 90)
			(layer "F.Fab")
			(hide yes)
			(effects
				(font
					(size 1.27 1.27)
					(thickness 0.15)
				)
			)
		)
		(property "Manufacturer" "Murata"
			(at 0 0 90)
			(unlocked yes)
			(layer "B.Fab")
			(hide yes)
			(effects
				(font
					(size 1 1)
					(thickness 0.15)
				)
				(justify mirror)
			)
		)
		(property "MPN" "GRM155R71H103KA88D"
			(at 0 0 90)
			(unlocked yes)
			(layer "B.Fab")
			(hide yes)
			(effects
				(font
					(size 1 1)
					(thickness 0.15)
				)
				(justify mirror)
			)
		)
		(property "Val" "10n"
			(at 0 0 90)
			(unlocked yes)
			(layer "B.Fab")
			(hide yes)
			(effects
				(font
					(size 1 1)
					(thickness 0.15)
				)
				(justify mirror)
			)
		)
		(property "License" "Apache-2.0"
			(at 0 0 90)
			(unlocked yes)
			(layer "B.Fab")
			(hide yes)
			(effects
				(font
					(size 1 1)
					(thickness 0.15)
				)
				(justify mirror)
			)
		)
		(property "Author" "Antmicro"
			(at 0 0 90)
			(unlocked yes)
			(layer "B.Fab")
			(hide yes)
			(effects
				(font
					(size 1 1)
					(thickness 0.15)
				)
				(justify mirror)
			)
		)
		(property "Voltage" "50V"
			(at 0 0 90)
			(unlocked yes)
			(layer "B.Fab")
			(hide yes)
			(effects
				(font
					(size 1 1)
					(thickness 0.15)
				)
				(justify mirror)
			)
		)
		(property "Dielectric" "X7R"
			(at 0 0 90)
			(unlocked yes)
			(layer "B.Fab")
			(hide yes)
			(effects
				(font
					(size 1 1)
					(thickness 0.15)
				)
				(justify mirror)
			)
		)
		(sheetname "/Ethernet/")
		(sheetfile "ethernet.kicad_sch")
		(attr smd)
		(fp_rect
			(start -0.925 0.47)
			(end 0.925 -0.47)
			(stroke
				(width 0.05)
				(type default)
			)
			(fill no)
			(layer "B.CrtYd")
		)
		(fp_line
			(start 0.504 -0.248)
			(end -0.494 -0.248)
			(stroke
				(width 0.15)
				(type solid)
			)
			(layer "B.Fab")
		)
		(fp_line
			(start -0.494 -0.248)
			(end -0.494 0.25)
			(stroke
				(width 0.15)
				(type solid)
			)
			(layer "B.Fab")
		)
		(fp_line
			(start 0.504 0.25)
			(end 0.504 -0.248)
			(stroke
				(width 0.15)
				(type solid)
			)
			(layer "B.Fab")
		)
		(fp_line
			(start -0.494 0.25)
			(end 0.504 0.25)
			(stroke
				(width 0.15)
				(type solid)
			)
			(layer "B.Fab")
		)
		(fp_text user "Author: Antmicro"
			(at -0.939 -3.399 270)
			(layer "B.Fab")
			(effects
				(font
					(size 0.7 0.7)
					(thickness 0.15)
				)
				(justify left bottom mirror)
			)
		)
		(fp_text user "License: Apache-2.0"
			(at -0.939 -5.799 270)
			(layer "B.Fab")
			(effects
				(font
					(size 0.7 0.7)
					(thickness 0.15)
				)
				(justify left bottom mirror)
			)
		)
		(fp_text user "${REFERENCE}"
			(at -0.939 -4.599 270)
			(layer "B.Fab")
			(effects
				(font
					(size 0.7 0.7)
					(thickness 0.15)
				)
				(justify left bottom mirror)
			)
		)
		(pad "1" smd roundrect
			(at -0.48 0 90)
			(size 0.59 0.64)
			(layers "B.Cu" "B.Mask" "B.Paste")
			(roundrect_rratio 0.25)
			(net 797 "+1V8")
			(pintype "passive")
		)
		(pad "2" smd roundrect
			(at 0.48 0 90)
			(size 0.59 0.64)
			(layers "B.Cu" "B.Mask" "B.Paste")
			(roundrect_rratio 0.25)
			(net 1 "GND")
			(pintype "passive")
		)
	)
)
